;EXTENTS: -17.932 -13.933 84.068  93.067  
;LEADER: 12 
;HEADER: 
;CODE  : ASCII 
;FILE  : G:/<user>/F/F0T/F0T_Motherboard/J/brd/0324/07_Export_Files/Upload_report/03242023_DA0F0TMBIJ0_F0T_Motherboard_J_artwork/9324_DA0F0TMBIJ0_F0T_Motherboard_J_v01_20230324_0910_1-18.rou for board G:/<user>/F/F0T/F0T_Motherboard/J/brd/0324/07_Export_Files/Upload_report/03242023_DA0F0TMBIJ0_F0T_Motherboard_J_artwork/#Taaaacj19520.tmp, layers TOP to BOTTOM
%
G90
F1
M16
T01
M16
G00X0919791Y0154311
G40
M15
G01X0925091Y0154311
M16
G00X0919791Y0243798
G40
M15
G01X0925091Y0243798
M16
T04
M16
G00X0925988Y0321653
G40
M15
G01X0931488Y0321653
M16
T03
M16
G00X0365287Y0185236
G40
M15
G01X0371587Y0185236
M16
G00X0247176Y0185236
G40
M15
G01X0253476Y0185236
M16
T02
M16
G00X0097070Y1287664
G40
M15
G01X0101970Y1287664
M16
G00X0097070Y0744554
G40
M15
G01X0101970Y0744554
M16
G00X0097070Y1000853
G40
M15
G01X0101970Y1000853
M16
G00X0660570Y1287664
G40
M15
G01X0665470Y1287664
M16
G00X0660570Y0744554
G40
M15
G01X0665470Y0744554
M16
G00X0660570Y1000853
G40
M15
G01X0665470Y1000853
M16
G00X0630870Y1287664
G40
M15
G01X0635770Y1287664
M16
G00X0630870Y0744554
G40
M15
G01X0635770Y0744554
M16
G00X0630870Y1000853
G40
M15
G01X0635770Y1000853
M16
G00X0037670Y1287664
G40
M15
G01X0042570Y1287664
M16
G00X0037670Y0744554
G40
M15
G01X0042570Y0744554
M16
G00X0037670Y1000853
G40
M15
G01X0042570Y1000853
M16
G00X0067370Y1287664
G40
M15
G01X0072270Y1287664
M16
G00X0067370Y0744554
G40
M15
G01X0072270Y0744554
M16
G00X0067370Y1000853
G40
M15
G01X0072270Y1000853
M16
G00X0126770Y1287664
G40
M15
G01X0131670Y1287664
M16
G00X0126770Y0744554
G40
M15
G01X0131670Y0744554
M16
G00X0126770Y1000853
G40
M15
G01X0131670Y1000853
M16
G00X0156470Y1287664
G40
M15
G01X0161370Y1287664
M16
G00X0156470Y0744554
G40
M15
G01X0161370Y0744554
M16
G00X0156470Y1000853
G40
M15
G01X0161370Y1000853
M16
G00X0186170Y1287664
G40
M15
G01X0191070Y1287664
M16
G00X0186170Y0744554
G40
M15
G01X0191070Y0744554
M16
G00X0186170Y1000853
G40
M15
G01X0191070Y1000853
M16
G00X0215869Y1287664
G40
M15
G01X0220769Y1287664
M16
G00X0215869Y0744554
G40
M15
G01X0220769Y0744554
M16
G00X0215869Y1000853
G40
M15
G01X0220769Y1000853
M16
G00X0245569Y1287664
G40
M15
G01X0250469Y1287664
M16
G00X0245569Y0744554
G40
M15
G01X0250469Y0744554
M16
G00X0245569Y1000853
G40
M15
G01X0250469Y1000853
M16
G00X0690270Y1287664
G40
M15
G01X0695170Y1287664
M16
G00X0690270Y0744554
G40
M15
G01X0695170Y0744554
M16
G00X0690270Y1000853
G40
M15
G01X0695170Y1000853
M16
G00X0719970Y1287664
G40
M15
G01X0724870Y1287664
M16
G00X0719970Y0744554
G40
M15
G01X0724870Y0744554
M16
G00X0719970Y1000853
G40
M15
G01X0724870Y1000853
M16
G00X0749670Y1287664
G40
M15
G01X0754570Y1287664
M16
G00X0749670Y0744554
G40
M15
G01X0754570Y0744554
M16
G00X0749670Y1000853
G40
M15
G01X0754570Y1000853
M16
G00X0779370Y1287664
G40
M15
G01X0784270Y1287664
M16
G00X0779370Y0744554
G40
M15
G01X0784270Y0744554
M16
G00X0779370Y1000853
G40
M15
G01X0784270Y1000853
M16
G00X0809070Y1287664
G40
M15
G01X0813970Y1287664
M16
G00X0809070Y0744554
G40
M15
G01X0813970Y0744554
M16
G00X0809070Y1000853
G40
M15
G01X0813970Y1000853
M16
G00X0838770Y1287664
G40
M15
G01X0843670Y1287664
M16
G00X0838770Y0744554
G40
M15
G01X0843670Y0744554
M16
G00X0838770Y1000853
G40
M15
G01X0843670Y1000853
M16
G00X1013812Y1287664
G40
M15
G01X1018712Y1287664
M16
G00X1013812Y0744554
G40
M15
G01X1018712Y0744554
M16
G00X1013812Y1000853
G40
M15
G01X1018712Y1000853
M16
G00X1043512Y1287664
G40
M15
G01X1048412Y1287664
M16
G00X1043512Y0744554
G40
M15
G01X1048412Y0744554
M16
G00X1043512Y1000853
G40
M15
G01X1048412Y1000853
M16
G00X1073212Y1287664
G40
M15
G01X1078112Y1287664
M16
G00X1073212Y0744554
G40
M15
G01X1078112Y0744554
M16
G00X1073212Y1000853
G40
M15
G01X1078112Y1000853
M16
G00X1102912Y1287664
G40
M15
G01X1107812Y1287664
M16
G00X1102912Y0744554
G40
M15
G01X1107812Y0744554
M16
G00X1102912Y1000853
G40
M15
G01X1107812Y1000853
M16
G00X1132612Y1287664
G40
M15
G01X1137512Y1287664
M16
G00X1132612Y0744554
G40
M15
G01X1137512Y0744554
M16
G00X1132612Y1000853
G40
M15
G01X1137512Y1000853
M16
G00X1162312Y1287664
G40
M15
G01X1167212Y1287664
M16
G00X1162312Y0744554
G40
M15
G01X1167212Y0744554
M16
G00X1162312Y1000853
G40
M15
G01X1167212Y1000853
M16
G00X1192012Y1287664
G40
M15
G01X1196912Y1287664
M16
G00X1192012Y0744554
G40
M15
G01X1196912Y0744554
M16
G00X1192012Y1000853
G40
M15
G01X1196912Y1000853
M16
G00X1221712Y1287664
G40
M15
G01X1226612Y1287664
M16
G00X1221712Y0744554
G40
M15
G01X1226612Y0744554
M16
G00X1221712Y1000853
G40
M15
G01X1226612Y1000853
M16
G00X1607012Y1287664
G40
M15
G01X1611912Y1287664
M16
G00X1607012Y0744554
G40
M15
G01X1611912Y0744554
M16
G00X1607012Y1000853
G40
M15
G01X1611912Y1000853
M16
G00X1636711Y1287664
G40
M15
G01X1641611Y1287664
M16
G00X1636711Y0744554
G40
M15
G01X1641611Y0744554
M16
G00X1636711Y1000853
G40
M15
G01X1641611Y1000853
M16
G00X1666411Y1287664
G40
M15
G01X1671311Y1287664
M16
G00X1666411Y0744554
G40
M15
G01X1671311Y0744554
M16
G00X1666411Y1000853
G40
M15
G01X1671311Y1000853
M16
G00X1696111Y1287664
G40
M15
G01X1701011Y1287664
M16
G00X1696111Y0744554
G40
M15
G01X1701011Y0744554
M16
G00X1696111Y1000853
G40
M15
G01X1701011Y1000853
M16
G00X1725811Y1287664
G40
M15
G01X1730711Y1287664
M16
G00X1725811Y0744554
G40
M15
G01X1730711Y0744554
M16
G00X1725811Y1000853
G40
M15
G01X1730711Y1000853
M16
G00X1755511Y1287664
G40
M15
G01X1760411Y1287664
M16
G00X1755511Y0744554
G40
M15
G01X1760411Y0744554
M16
G00X1755511Y1000853
G40
M15
G01X1760411Y1000853
M16
G00X1785211Y1287664
G40
M15
G01X1790111Y1287664
M16
G00X1785211Y0744554
G40
M15
G01X1790111Y0744554
M16
G00X1785211Y1000853
G40
M15
G01X1790111Y1000853
M16
G00X1814911Y1287664
G40
M15
G01X1819811Y1287664
M16
G00X1814911Y0744554
G40
M15
G01X1819811Y0744554
M16
G00X1814911Y1000853
G40
M15
G01X1819811Y1000853
M16
G40
M30
